(kicad_pcb
	(version 20260206)
	(generator "pcbnew")
	(generator_version "10.0")
	(general
		(thickness 1.6)
		(legacy_teardrops no)
	)
	(paper "A4")
	(title_block
		(title "baseboard — 13948-1b.1110WZS1818.brd")
		(comment 1 "Honey Badger (Wiwynn) / footprints 1526-1533 of 2523")
	)
	(layers
		(0 "F.Cu" signal "TOP")
		(4 "In1.Cu" signal "L2GND")
		(6 "In2.Cu" signal "L3")
		(8 "In3.Cu" signal "L4VCC")
		(10 "In4.Cu" signal "L5VCC")
		(12 "In5.Cu" signal "L6")
		(14 "In6.Cu" signal "L7GND")
		(2 "B.Cu" signal "BOTTOM")
		(9 "F.Adhes" user "F.Adhesive")
		(11 "B.Adhes" user "B.Adhesive")
		(13 "F.Paste" user "Package Geometry/Pastemask Top")
		(15 "B.Paste" user "Package Geometry/Pastemask Bottom")
		(5 "F.SilkS" user "Ref Des/Silkscreen Top")
		(7 "B.SilkS" user "Ref Des/Silkscreen Bottom")
		(1 "F.Mask" user "Board Geometry/Soldermask Top")
		(3 "B.Mask" user "Board Geometry/Soldermask Bottom")
		(17 "Dwgs.User" user "User.Drawings")
		(19 "Cmts.User" user "User.Comments")
		(21 "Eco1.User" user "User.Eco1")
		(23 "Eco2.User" user "User.Eco2")
		(25 "Edge.Cuts" user "Board Geometry/Outline")
		(27 "Margin" user)
		(31 "F.CrtYd" user "Package Geometry/Place Bound Top")
		(29 "B.CrtYd" user "Package Geometry/Place Bound Bottom")
		(35 "F.Fab" user "Ref Des/Assembly Top")
		(33 "B.Fab" user "Ref Des/Assembly Bottom")
	)
	(footprint ""
		(layer "F.Cu")
		(at 269.739872 -55.698136 90)
		(property "Reference" "PR117"
			(at 0 0 90)
			(layer "F.SilkS")
			(hide yes)
			(effects
				(font
					(size 1.27 1.27)
				)
			)
		)
		(property "Value" "0R2J-2-GP"
			(at 0.064008 -3.993896 90)
			(unlocked yes)
			(layer "F.Fab")
			(hide yes)
			(effects
				(font
					(size 1.016 1.016)
					(thickness 0.1524)
				)
			)
		)
		(property "Device Type" "R402H16"
			(at 0.064008 -5.517896 90)
			(unlocked yes)
			(layer "F.Fab")
			(hide yes)
			(effects
				(font
					(size 1.016 1.016)
					(thickness 0.1524)
				)
			)
		)
		(duplicate_pad_numbers_are_jumpers no)
		(fp_line
			(start 0.508 -0.9398)
			(end -0.508 -0.9398)
			(stroke
				(width 0.1524)
				(type default)
			)
			(layer "F.SilkS")
		)
		(fp_line
			(start -0.508 -0.9398)
			(end -0.508 0.9398)
			(stroke
				(width 0.1524)
				(type default)
			)
			(layer "F.SilkS")
		)
		(fp_rect
			(start -0.508 0.9398)
			(end 0.508 -0.9398)
			(stroke
				(width 0)
				(type default)
			)
			(fill no)
			(layer "F.CrtYd")
		)
		(fp_rect
			(start -0.508 0.9398)
			(end 0.508 -0.9398)
			(stroke
				(width 0)
				(type default)
			)
			(fill no)
			(layer "F.Fab")
		)
		(pad "1" smd custom
			(at 0 -0.4445 90)
			(size 0.1397 0.1397)
			(layers "F.Cu" "F.Mask" "F.Paste")
			(net "P0V9_E_PG")
			(options
				(clearance outline)
				(anchor circle)
			)
			(primitives
				(gr_poly
					(pts
						(arc
							(start -0.1778 -0.2794)
							(mid -0.249642 -0.249642)
							(end -0.2794 -0.1778)
						)
						(arc
							(start -0.2794 0.1778)
							(mid -0.249642 0.249642)
							(end -0.1778 0.2794)
						)
						(arc
							(start 0.1778 0.2794)
							(mid 0.249642 0.249642)
							(end 0.2794 0.1778)
						)
						(arc
							(start 0.2794 -0.1778)
							(mid 0.249642 -0.249642)
							(end 0.1778 -0.2794)
						)
					)
					(width 0)
					(fill yes)
				)
			)
		)
		(pad "2" smd custom
			(at 0 0.4445 90)
			(size 0.1397 0.1397)
			(layers "F.Cu" "F.Mask" "F.Paste")
			(net "P3V3_EN_B")
			(options
				(clearance outline)
				(anchor circle)
			)
			(primitives
				(gr_poly
					(pts
						(arc
							(start -0.1778 -0.2794)
							(mid -0.249642 -0.249642)
							(end -0.2794 -0.1778)
						)
						(arc
							(start -0.2794 0.1778)
							(mid -0.249642 0.249642)
							(end -0.1778 0.2794)
						)
						(arc
							(start 0.1778 0.2794)
							(mid 0.249642 0.249642)
							(end 0.2794 0.1778)
						)
						(arc
							(start 0.2794 -0.1778)
							(mid 0.249642 -0.249642)
							(end 0.1778 -0.2794)
						)
					)
					(width 0)
					(fill yes)
				)
			)
		)
	)
	(footprint ""
		(layer "F.Cu")
		(at 186.244992 -48.133 -90)
		(property "Reference" "R21"
			(at 0 0 270)
			(layer "F.SilkS")
			(hide yes)
			(effects
				(font
					(size 1.27 1.27)
				)
			)
		)
		(property "Value" "10KR2F-2-GP"
			(at 0.064008 -3.993896 270)
			(unlocked yes)
			(layer "F.Fab")
			(hide yes)
			(effects
				(font
					(size 1.016 1.016)
					(thickness 0.1524)
				)
			)
		)
		(property "Device Type" "R402H16"
			(at 0.064008 -5.517896 270)
			(unlocked yes)
			(layer "F.Fab")
			(hide yes)
			(effects
				(font
					(size 1.016 1.016)
					(thickness 0.1524)
				)
			)
		)
		(duplicate_pad_numbers_are_jumpers no)
		(fp_line
			(start -0.508 -0.9398)
			(end -0.508 0.9398)
			(stroke
				(width 0.1524)
				(type default)
			)
			(layer "F.SilkS")
		)
		(fp_line
			(start 0.508 -0.9398)
			(end -0.508 -0.9398)
			(stroke
				(width 0.1524)
				(type default)
			)
			(layer "F.SilkS")
		)
		(fp_rect
			(start -0.508 0.9398)
			(end 0.508 -0.9398)
			(stroke
				(width 0)
				(type default)
			)
			(fill no)
			(layer "F.CrtYd")
		)
		(fp_rect
			(start -0.508 0.9398)
			(end 0.508 -0.9398)
			(stroke
				(width 0)
				(type default)
			)
			(fill no)
			(layer "F.Fab")
		)
		(pad "1" smd custom
			(at 0 -0.4445 270)
			(size 0.1397 0.1397)
			(layers "F.Cu" "F.Mask" "F.Paste")
			(net "PRSNT_MSB_AND_1")
			(options
				(clearance outline)
				(anchor circle)
			)
			(primitives
				(gr_poly
					(pts
						(arc
							(start -0.1778 -0.2794)
							(mid -0.249642 -0.249642)
							(end -0.2794 -0.1778)
						)
						(arc
							(start -0.2794 0.1778)
							(mid -0.249642 0.249642)
							(end -0.1778 0.2794)
						)
						(arc
							(start 0.1778 0.2794)
							(mid 0.249642 0.249642)
							(end 0.2794 0.1778)
						)
						(arc
							(start 0.2794 -0.1778)
							(mid 0.249642 -0.249642)
							(end 0.1778 -0.2794)
						)
					)
					(width 0)
					(fill yes)
				)
			)
		)
		(pad "2" smd custom
			(at 0 0.4445 270)
			(size 0.1397 0.1397)
			(layers "F.Cu" "F.Mask" "F.Paste")
			(net "P3V3_STBY")
			(options
				(clearance outline)
				(anchor circle)
			)
			(primitives
				(gr_poly
					(pts
						(arc
							(start -0.1778 -0.2794)
							(mid -0.249642 -0.249642)
							(end -0.2794 -0.1778)
						)
						(arc
							(start -0.2794 0.1778)
							(mid -0.249642 0.249642)
							(end -0.1778 0.2794)
						)
						(arc
							(start 0.1778 0.2794)
							(mid 0.249642 0.249642)
							(end 0.2794 0.1778)
						)
						(arc
							(start 0.2794 -0.1778)
							(mid 0.249642 -0.249642)
							(end 0.1778 -0.2794)
						)
					)
					(width 0)
					(fill yes)
				)
			)
		)
	)
	(footprint ""
		(layer "F.Cu")
		(at 276.1488 -168.8846)
		(property "Reference" "TP88"
			(at 0 0 0)
			(layer "F.SilkS")
			(hide yes)
			(effects
				(font
					(size 1.27 1.27)
				)
			)
		)
		(property "Value" "TPAD28"
			(at 0.0127 -1.8034 0)
			(unlocked yes)
			(layer "F.Fab")
			(hide yes)
			(effects
				(font
					(size 1.016 1.016)
					(thickness 0.1524)
				)
			)
		)
		(property "Device Type" "TPAD28"
			(at 0.0127 -3.3274 0)
			(unlocked yes)
			(layer "F.Fab")
			(hide yes)
			(effects
				(font
					(size 1.016 1.016)
					(thickness 0.1524)
				)
			)
		)
		(duplicate_pad_numbers_are_jumpers no)
		(fp_poly
			(pts
				(arc
					(start 0.3556 0)
					(mid -0.3556 0)
					(end 0.3556 0)
				)
			)
			(stroke
				(width 0)
				(type default)
			)
			(fill no)
			(layer "F.CrtYd")
		)
		(fp_poly
			(pts
				(arc
					(start 0.6096 0)
					(mid -0.6096 0)
					(end 0.6096 0)
				)
			)
			(stroke
				(width 0)
				(type default)
			)
			(fill no)
			(layer "F.Fab")
		)
		(pad "1" smd circle
			(at 0 0)
			(size 0.7112 0.7112)
			(layers "F.Cu" "F.Mask" "F.Paste")
			(net "BMC_MSB_I2C_E_ALERT_#")
		)
	)
	(footprint ""
		(layer "F.Cu")
		(at 116.47297 -74.93)
		(property "Reference" "SR801"
			(at 0 0 0)
			(layer "F.SilkS")
			(hide yes)
			(effects
				(font
					(size 1.27 1.27)
				)
			)
		)
		(property "Value" "4K75R2F-1-GP"
			(at 0.064008 -3.993896 0)
			(unlocked yes)
			(layer "F.Fab")
			(hide yes)
			(effects
				(font
					(size 1.016 1.016)
					(thickness 0.1524)
				)
			)
		)
		(property "Device Type" "R402H16"
			(at 0.064008 -5.517896 0)
			(unlocked yes)
			(layer "F.Fab")
			(hide yes)
			(effects
				(font
					(size 1.016 1.016)
					(thickness 0.1524)
				)
			)
		)
		(duplicate_pad_numbers_are_jumpers no)
		(fp_line
			(start -0.508 -0.9398)
			(end -0.508 0.9398)
			(stroke
				(width 0.1524)
				(type default)
			)
			(layer "F.SilkS")
		)
		(fp_line
			(start 0.508 -0.9398)
			(end -0.508 -0.9398)
			(stroke
				(width 0.1524)
				(type default)
			)
			(layer "F.SilkS")
		)
		(fp_rect
			(start -0.508 0.9398)
			(end 0.508 -0.9398)
			(stroke
				(width 0)
				(type default)
			)
			(fill no)
			(layer "F.CrtYd")
		)
		(fp_rect
			(start -0.508 0.9398)
			(end 0.508 -0.9398)
			(stroke
				(width 0)
				(type default)
			)
			(fill no)
			(layer "F.Fab")
		)
		(pad "1" smd custom
			(at 0 -0.4445)
			(size 0.1397 0.1397)
			(layers "F.Cu" "F.Mask" "F.Paste")
			(net "TEST_MUX_46")
			(options
				(clearance outline)
				(anchor circle)
			)
			(primitives
				(gr_poly
					(pts
						(arc
							(start -0.1778 -0.2794)
							(mid -0.249642 -0.249642)
							(end -0.2794 -0.1778)
						)
						(arc
							(start -0.2794 0.1778)
							(mid -0.249642 0.249642)
							(end -0.1778 0.2794)
						)
						(arc
							(start 0.1778 0.2794)
							(mid 0.249642 0.249642)
							(end 0.2794 0.1778)
						)
						(arc
							(start 0.2794 -0.1778)
							(mid 0.249642 -0.249642)
							(end 0.1778 -0.2794)
						)
					)
					(width 0)
					(fill yes)
				)
			)
		)
		(pad "2" smd custom
			(at 0 0.4445)
			(size 0.1397 0.1397)
			(layers "F.Cu" "F.Mask" "F.Paste")
			(net "GND")
			(options
				(clearance outline)
				(anchor circle)
			)
			(primitives
				(gr_poly
					(pts
						(arc
							(start -0.1778 -0.2794)
							(mid -0.249642 -0.249642)
							(end -0.2794 -0.1778)
						)
						(arc
							(start -0.2794 0.1778)
							(mid -0.249642 0.249642)
							(end -0.1778 0.2794)
						)
						(arc
							(start 0.1778 0.2794)
							(mid 0.249642 0.249642)
							(end 0.2794 0.1778)
						)
						(arc
							(start 0.2794 -0.1778)
							(mid 0.249642 -0.249642)
							(end 0.1778 -0.2794)
						)
					)
					(width 0)
					(fill yes)
				)
			)
		)
	)
	(footprint ""
		(layer "F.Cu")
		(at 195.199 -216.789 90)
		(property "Reference" "R326"
			(at 0 0 90)
			(layer "F.SilkS")
			(hide yes)
			(effects
				(font
					(size 1.27 1.27)
				)
			)
		)
		(property "Value" "4K7R2F-GP"
			(at 0.064008 -3.993896 90)
			(unlocked yes)
			(layer "F.Fab")
			(hide yes)
			(effects
				(font
					(size 1.016 1.016)
					(thickness 0.1524)
				)
			)
		)
		(property "Device Type" "R402H16"
			(at 0.064008 -5.517896 90)
			(unlocked yes)
			(layer "F.Fab")
			(hide yes)
			(effects
				(font
					(size 1.016 1.016)
					(thickness 0.1524)
				)
			)
		)
		(duplicate_pad_numbers_are_jumpers no)
		(fp_line
			(start 0.508 -0.9398)
			(end -0.508 -0.9398)
			(stroke
				(width 0.1524)
				(type default)
			)
			(layer "F.SilkS")
		)
		(fp_line
			(start -0.508 -0.9398)
			(end -0.508 0.9398)
			(stroke
				(width 0.1524)
				(type default)
			)
			(layer "F.SilkS")
		)
		(fp_rect
			(start -0.508 0.9398)
			(end 0.508 -0.9398)
			(stroke
				(width 0)
				(type default)
			)
			(fill no)
			(layer "F.CrtYd")
		)
		(fp_rect
			(start -0.508 0.9398)
			(end 0.508 -0.9398)
			(stroke
				(width 0)
				(type default)
			)
			(fill no)
			(layer "F.Fab")
		)
		(pad "1" smd custom
			(at 0 -0.4445 90)
			(size 0.1397 0.1397)
			(layers "F.Cu" "F.Mask" "F.Paste")
			(net "P3V3_STBY")
			(options
				(clearance outline)
				(anchor circle)
			)
			(primitives
				(gr_poly
					(pts
						(arc
							(start -0.1778 -0.2794)
							(mid -0.249642 -0.249642)
							(end -0.2794 -0.1778)
						)
						(arc
							(start -0.2794 0.1778)
							(mid -0.249642 0.249642)
							(end -0.1778 0.2794)
						)
						(arc
							(start 0.1778 0.2794)
							(mid 0.249642 0.249642)
							(end 0.2794 0.1778)
						)
						(arc
							(start 0.2794 -0.1778)
							(mid 0.249642 -0.249642)
							(end 0.1778 -0.2794)
						)
					)
					(width 0)
					(fill yes)
				)
			)
		)
		(pad "2" smd custom
			(at 0 0.4445 90)
			(size 0.1397 0.1397)
			(layers "F.Cu" "F.Mask" "F.Paste")
			(net "BMC_RSTBTN_N")
			(options
				(clearance outline)
				(anchor circle)
			)
			(primitives
				(gr_poly
					(pts
						(arc
							(start -0.1778 -0.2794)
							(mid -0.249642 -0.249642)
							(end -0.2794 -0.1778)
						)
						(arc
							(start -0.2794 0.1778)
							(mid -0.249642 0.249642)
							(end -0.1778 0.2794)
						)
						(arc
							(start 0.1778 0.2794)
							(mid 0.249642 0.249642)
							(end 0.2794 0.1778)
						)
						(arc
							(start 0.2794 -0.1778)
							(mid 0.249642 -0.249642)
							(end 0.1778 -0.2794)
						)
					)
					(width 0)
					(fill yes)
				)
			)
		)
	)
	(footprint ""
		(layer "F.Cu")
		(at 274.193 -174.625 90)
		(property "Reference" "R352"
			(at 0 0 90)
			(layer "F.SilkS")
			(hide yes)
			(effects
				(font
					(size 1.27 1.27)
				)
			)
		)
		(property "Value" "3K3R2F-2-GP"
			(at 0.064008 -3.993896 90)
			(unlocked yes)
			(layer "F.Fab")
			(hide yes)
			(effects
				(font
					(size 1.016 1.016)
					(thickness 0.1524)
				)
			)
		)
		(property "Device Type" "R402H16"
			(at 0.064008 -5.517896 90)
			(unlocked yes)
			(layer "F.Fab")
			(hide yes)
			(effects
				(font
					(size 1.016 1.016)
					(thickness 0.1524)
				)
			)
		)
		(duplicate_pad_numbers_are_jumpers no)
		(fp_line
			(start 0.508 -0.9398)
			(end -0.508 -0.9398)
			(stroke
				(width 0.1524)
				(type default)
			)
			(layer "F.SilkS")
		)
		(fp_line
			(start -0.508 -0.9398)
			(end -0.508 0.9398)
			(stroke
				(width 0.1524)
				(type default)
			)
			(layer "F.SilkS")
		)
		(fp_rect
			(start -0.508 0.9398)
			(end 0.508 -0.9398)
			(stroke
				(width 0)
				(type default)
			)
			(fill no)
			(layer "F.CrtYd")
		)
		(fp_rect
			(start -0.508 0.9398)
			(end 0.508 -0.9398)
			(stroke
				(width 0)
				(type default)
			)
			(fill no)
			(layer "F.Fab")
		)
		(pad "1" smd custom
			(at 0 -0.4445 90)
			(size 0.1397 0.1397)
			(layers "F.Cu" "F.Mask" "F.Paste")
			(net "P3V3_STBY")
			(options
				(clearance outline)
				(anchor circle)
			)
			(primitives
				(gr_poly
					(pts
						(arc
							(start -0.1778 -0.2794)
							(mid -0.249642 -0.249642)
							(end -0.2794 -0.1778)
						)
						(arc
							(start -0.2794 0.1778)
							(mid -0.249642 0.249642)
							(end -0.1778 0.2794)
						)
						(arc
							(start 0.1778 0.2794)
							(mid 0.249642 0.249642)
							(end 0.2794 0.1778)
						)
						(arc
							(start 0.2794 -0.1778)
							(mid 0.249642 -0.249642)
							(end 0.1778 -0.2794)
						)
					)
					(width 0)
					(fill yes)
				)
			)
		)
		(pad "2" smd custom
			(at 0 0.4445 90)
			(size 0.1397 0.1397)
			(layers "F.Cu" "F.Mask" "F.Paste")
			(net "ROMA11")
			(options
				(clearance outline)
				(anchor circle)
			)
			(primitives
				(gr_poly
					(pts
						(arc
							(start -0.1778 -0.2794)
							(mid -0.249642 -0.249642)
							(end -0.2794 -0.1778)
						)
						(arc
							(start -0.2794 0.1778)
							(mid -0.249642 0.249642)
							(end -0.1778 0.2794)
						)
						(arc
							(start 0.1778 0.2794)
							(mid 0.249642 0.249642)
							(end 0.2794 0.1778)
						)
						(arc
							(start 0.2794 -0.1778)
							(mid 0.249642 -0.249642)
							(end 0.1778 -0.2794)
						)
					)
					(width 0)
					(fill yes)
				)
			)
		)
	)
	(footprint ""
		(layer "F.Cu")
		(at 261.039864 -231.004872)
		(property "Reference" "PR90"
			(at 0 0 0)
			(layer "F.SilkS")
			(hide yes)
			(effects
				(font
					(size 1.27 1.27)
				)
			)
		)
		(property "Value" "0R2J-2-GP"
			(at 0.064008 -3.993896 0)
			(unlocked yes)
			(layer "F.Fab")
			(hide yes)
			(effects
				(font
					(size 1.016 1.016)
					(thickness 0.1524)
				)
			)
		)
		(property "Device Type" "R402H16"
			(at 0.064008 -5.517896 0)
			(unlocked yes)
			(layer "F.Fab")
			(hide yes)
			(effects
				(font
					(size 1.016 1.016)
					(thickness 0.1524)
				)
			)
		)
		(duplicate_pad_numbers_are_jumpers no)
		(fp_line
			(start -0.508 -0.9398)
			(end -0.508 0.9398)
			(stroke
				(width 0.1524)
				(type default)
			)
			(layer "F.SilkS")
		)
		(fp_line
			(start 0.508 -0.9398)
			(end -0.508 -0.9398)
			(stroke
				(width 0.1524)
				(type default)
			)
			(layer "F.SilkS")
		)
		(fp_rect
			(start -0.508 0.9398)
			(end 0.508 -0.9398)
			(stroke
				(width 0)
				(type default)
			)
			(fill no)
			(layer "F.CrtYd")
		)
		(fp_rect
			(start -0.508 0.9398)
			(end 0.508 -0.9398)
			(stroke
				(width 0)
				(type default)
			)
			(fill no)
			(layer "F.Fab")
		)
		(pad "1" smd custom
			(at 0 -0.4445)
			(size 0.1397 0.1397)
			(layers "F.Cu" "F.Mask" "F.Paste")
			(net "P3V3_STBY")
			(options
				(clearance outline)
				(anchor circle)
			)
			(primitives
				(gr_poly
					(pts
						(arc
							(start -0.1778 -0.2794)
							(mid -0.249642 -0.249642)
							(end -0.2794 -0.1778)
						)
						(arc
							(start -0.2794 0.1778)
							(mid -0.249642 0.249642)
							(end -0.1778 0.2794)
						)
						(arc
							(start 0.1778 0.2794)
							(mid 0.249642 0.249642)
							(end 0.2794 0.1778)
						)
						(arc
							(start 0.2794 -0.1778)
							(mid 0.249642 -0.249642)
							(end 0.1778 -0.2794)
						)
					)
					(width 0)
					(fill yes)
				)
			)
		)
		(pad "2" smd custom
			(at 0 0.4445)
			(size 0.1397 0.1397)
			(layers "F.Cu" "F.Mask" "F.Paste")
			(net "TPS74801_1V26_STBY_BIAS")
			(options
				(clearance outline)
				(anchor circle)
			)
			(primitives
				(gr_poly
					(pts
						(arc
							(start -0.1778 -0.2794)
							(mid -0.249642 -0.249642)
							(end -0.2794 -0.1778)
						)
						(arc
							(start -0.2794 0.1778)
							(mid -0.249642 0.249642)
							(end -0.1778 0.2794)
						)
						(arc
							(start 0.1778 0.2794)
							(mid 0.249642 0.249642)
							(end 0.2794 0.1778)
						)
						(arc
							(start 0.2794 -0.1778)
							(mid 0.249642 -0.249642)
							(end 0.1778 -0.2794)
						)
					)
					(width 0)
					(fill yes)
				)
			)
		)
	)
	(footprint ""
		(layer "F.Cu")
		(at 315.595 -149.352 90)
		(property "Reference" "TP800"
			(at 0 0 90)
			(layer "F.SilkS")
			(hide yes)
			(effects
				(font
					(size 1.27 1.27)
				)
			)
		)
		(property "Value" "TPAD28"
			(at -0.0127 -1.6637 90)
			(unlocked yes)
			(layer "F.Fab")
			(hide yes)
			(effects
				(font
					(size 1.016 1.016)
					(thickness 0.1524)
				)
			)
		)
		(property "Device Type" "TPAD28"
			(at -0.0127 -3.1877 90)
			(unlocked yes)
			(layer "F.Fab")
			(hide yes)
			(effects
				(font
					(size 1.016 1.016)
					(thickness 0.1524)
				)
			)
		)
		(duplicate_pad_numbers_are_jumpers no)
		(fp_poly
			(pts
				(arc
					(start 0 0.3556)
					(mid 0 -0.3556)
					(end 0 0.3556)
				)
			)
			(stroke
				(width 0)
				(type default)
			)
			(fill no)
			(layer "F.CrtYd")
		)
		(fp_poly
			(pts
				(arc
					(start 0 0.6096)
					(mid 0 -0.6096)
					(end 0 0.6096)
				)
			)
			(stroke
				(width 0)
				(type default)
			)
			(fill no)
			(layer "F.Fab")
		)
		(pad "1" smd circle
			(at 0 0 90)
			(size 0.7112 0.7112)
			(layers "F.Cu" "F.Mask" "F.Paste")
			(net "RTC_CLK_OUT")
		)
	)
)
